# S9S_MB_2U (Grand Teton) — schematic netlist excerpt (pin names and nets, part order shuffled) for the footprints in the layout excerpt that follows; sources: Cadence DE-HDL packaged netlist, KiCad conversion of 03242023_DA0F0TMBIJ0_F0T_Motherboard_J_brd_V01_OCP.brd

R208  Q_RES  0 5% CHIP  pkg 0402LF  page 122 : A = H_CPU0_MEMHOT_IN_LVC1_R_N ; B = H_CPU0_MEMHOT_IN_LVC1_R1_N
R456  Q_RES  10K 1% CHIP  pkg 0402LF  page 204 : A = P3V3_AUX ; B = PU_PCH_PMCALERT_N

(kicad_pcb
	(version 20260206)
	(generator "pcbnew")
	(generator_version "10.0")
	(general
		(thickness 1.6)
		(legacy_teardrops no)
	)
	(paper "A4")
	(title_block
		(title "03242023_DA0F0TMBIJ0_F0T_Motherboard_J_brd_V01_OCP.brd")
		(comment 1 "Grand Teton / footprints 3363-3364 of 6105")
	)
	(layers
		(0 "F.Cu" signal "TOP")
		(4 "In1.Cu" signal "GND")
		(6 "In2.Cu" signal "IN1")
		(8 "In3.Cu" signal "GND1")
		(10 "In4.Cu" signal "IN2")
		(12 "In5.Cu" signal "GND2")
		(14 "In6.Cu" signal "IN3")
		(16 "In7.Cu" signal "GND3")
		(18 "In8.Cu" signal "VCC")
		(20 "In9.Cu" signal "VCC1")
		(22 "In10.Cu" signal "GND4")
		(24 "In11.Cu" signal "IN4")
		(26 "In12.Cu" signal "GND5")
		(28 "In13.Cu" signal "IN5")
		(30 "In14.Cu" signal "GND6")
		(32 "In15.Cu" signal "IN6")
		(34 "In16.Cu" signal "GND7")
		(2 "B.Cu" signal "BOTTOM")
		(9 "F.Adhes" user "F.Adhesive")
		(11 "B.Adhes" user "B.Adhesive")
		(13 "F.Paste" user "Package Geometry/Pastemask Top")
		(15 "B.Paste" user "Package Geometry/Pastemask Bottom")
		(5 "F.SilkS" user "Ref Des/Silkscreen Top")
		(7 "B.SilkS" user "Ref Des/Silkscreen Bottom")
		(1 "F.Mask" user "Board Geometry/Soldermask Top")
		(3 "B.Mask" user "Board Geometry/Soldermask Bottom")
		(17 "Dwgs.User" user "User.Drawings")
		(19 "Cmts.User" user "User.Comments")
		(21 "Eco1.User" user "User.Eco1")
		(23 "Eco2.User" user "User.Eco2")
		(25 "Edge.Cuts" user "Board Geometry/Outline")
		(27 "Margin" user)
		(31 "F.CrtYd" user "Package Geometry/Place Bound Top")
		(29 "B.CrtYd" user "Package Geometry/Place Bound Bottom")
		(35 "F.Fab" user "Ref Des/Assembly Top")
		(33 "B.Fab" user "Ref Des/Assembly Bottom")
	)
	(footprint ""
		(layer "F.Cu")
		(at 181.15788 -99.659948 -90)
		(property "Reference" "R208"
			(at 0 0 270)
			(layer "F.SilkS")
			(hide yes)
			(effects
				(font
					(size 1.27 1.27)
				)
			)
		)
		(property "Value" ""
			(at 0 0 270)
			(layer "F.Fab")
			(effects
				(font
					(size 1.27 1.27)
				)
			)
		)
		(duplicate_pad_numbers_are_jumpers no)
		(fp_line
			(start -0.7874 0.4064)
			(end -0.7874 -0.4064)
			(stroke
				(width 0.1524)
				(type default)
			)
			(layer "F.SilkS")
		)
		(fp_line
			(start 0.7874 0.4064)
			(end -0.7874 0.4064)
			(stroke
				(width 0.1524)
				(type default)
			)
			(layer "F.SilkS")
		)
		(fp_line
			(start -0.7874 -0.4064)
			(end 0.7874 -0.4064)
			(stroke
				(width 0.1524)
				(type default)
			)
			(layer "F.SilkS")
		)
		(fp_line
			(start 0.7874 -0.4064)
			(end 0.7874 0.4064)
			(stroke
				(width 0.1524)
				(type default)
			)
			(layer "F.SilkS")
		)
		(fp_line
			(start -0.67945 0.3048)
			(end -0.67945 -0.305054)
			(stroke
				(width 0.1)
				(type default)
			)
			(layer "F.Fab")
		)
		(fp_line
			(start -0.12065 0.3048)
			(end -0.67945 0.3048)
			(stroke
				(width 0.1)
				(type default)
			)
			(layer "F.Fab")
		)
		(fp_line
			(start 0.120396 0.3048)
			(end 0.120396 0.2794)
			(stroke
				(width 0.1)
				(type default)
			)
			(layer "F.Fab")
		)
		(fp_line
			(start 0.67945 0.3048)
			(end 0.120396 0.3048)
			(stroke
				(width 0.1)
				(type default)
			)
			(layer "F.Fab")
		)
		(fp_line
			(start -0.12065 0.2794)
			(end -0.12065 0.3048)
			(stroke
				(width 0.1)
				(type default)
			)
			(layer "F.Fab")
		)
		(fp_line
			(start 0.120396 0.2794)
			(end -0.12065 0.2794)
			(stroke
				(width 0.1)
				(type default)
			)
			(layer "F.Fab")
		)
		(fp_line
			(start -0.12065 -0.2794)
			(end 0.12065 -0.2794)
			(stroke
				(width 0.1)
				(type default)
			)
			(layer "F.Fab")
		)
		(fp_line
			(start 0.12065 -0.2794)
			(end 0.12065 -0.3048)
			(stroke
				(width 0.1)
				(type default)
			)
			(layer "F.Fab")
		)
		(fp_line
			(start 0.12065 -0.3048)
			(end 0.67945 -0.3048)
			(stroke
				(width 0.1)
				(type default)
			)
			(layer "F.Fab")
		)
		(fp_line
			(start 0.67945 -0.3048)
			(end 0.67945 0.3048)
			(stroke
				(width 0.1)
				(type default)
			)
			(layer "F.Fab")
		)
		(fp_line
			(start -0.67945 -0.305054)
			(end -0.12065 -0.305054)
			(stroke
				(width 0.1)
				(type default)
			)
			(layer "F.Fab")
		)
		(fp_line
			(start -0.12065 -0.305054)
			(end -0.12065 -0.2794)
			(stroke
				(width 0.1)
				(type default)
			)
			(layer "F.Fab")
		)
		(pad "1" smd circle
			(at -0.40005 0 270)
			(size 0 0)
			(layers "F.Cu" "F.Mask" "F.Paste")
			(net "H_CPU0_MEMHOT_IN_LVC1_R_N")
		)
		(pad "2" smd circle
			(at 0.40005 0 270)
			(size 0 0)
			(layers "F.Cu" "F.Mask" "F.Paste")
			(net "H_CPU0_MEMHOT_IN_LVC1_R1_N")
		)
	)
	(footprint ""
		(layer "F.Cu")
		(at 322.095622 -59.299348)
		(property "Reference" "R456"
			(at 0 0 0)
			(layer "F.SilkS")
			(hide yes)
			(effects
				(font
					(size 1.27 1.27)
				)
			)
		)
		(property "Value" ""
			(at 0 0 0)
			(layer "F.Fab")
			(effects
				(font
					(size 1.27 1.27)
				)
			)
		)
		(duplicate_pad_numbers_are_jumpers no)
		(fp_line
			(start -0.7874 -0.4064)
			(end 0.7874 -0.4064)
			(stroke
				(width 0.1524)
				(type default)
			)
			(layer "F.SilkS")
		)
		(fp_line
			(start -0.7874 0.4064)
			(end -0.7874 -0.4064)
			(stroke
				(width 0.1524)
				(type default)
			)
			(layer "F.SilkS")
		)
		(fp_line
			(start 0.7874 -0.4064)
			(end 0.7874 0.4064)
			(stroke
				(width 0.1524)
				(type default)
			)
			(layer "F.SilkS")
		)
		(fp_line
			(start 0.7874 0.4064)
			(end -0.7874 0.4064)
			(stroke
				(width 0.1524)
				(type default)
			)
			(layer "F.SilkS")
		)
		(fp_line
			(start -0.67945 -0.305054)
			(end -0.12065 -0.305054)
			(stroke
				(width 0.1)
				(type default)
			)
			(layer "F.Fab")
		)
		(fp_line
			(start -0.67945 0.3048)
			(end -0.67945 -0.305054)
			(stroke
				(width 0.1)
				(type default)
			)
			(layer "F.Fab")
		)
		(fp_line
			(start -0.12065 -0.305054)
			(end -0.12065 -0.2794)
			(stroke
				(width 0.1)
				(type default)
			)
			(layer "F.Fab")
		)
		(fp_line
			(start -0.12065 -0.2794)
			(end 0.12065 -0.2794)
			(stroke
				(width 0.1)
				(type default)
			)
			(layer "F.Fab")
		)
		(fp_line
			(start -0.12065 0.2794)
			(end -0.12065 0.3048)
			(stroke
				(width 0.1)
				(type default)
			)
			(layer "F.Fab")
		)
		(fp_line
			(start -0.12065 0.3048)
			(end -0.67945 0.3048)
			(stroke
				(width 0.1)
				(type default)
			)
			(layer "F.Fab")
		)
		(fp_line
			(start 0.120396 0.2794)
			(end -0.12065 0.2794)
			(stroke
				(width 0.1)
				(type default)
			)
			(layer "F.Fab")
		)
		(fp_line
			(start 0.120396 0.3048)
			(end 0.120396 0.2794)
			(stroke
				(width 0.1)
				(type default)
			)
			(layer "F.Fab")
		)
		(fp_line
			(start 0.12065 -0.3048)
			(end 0.67945 -0.3048)
			(stroke
				(width 0.1)
				(type default)
			)
			(layer "F.Fab")
		)
		(fp_line
			(start 0.12065 -0.2794)
			(end 0.12065 -0.3048)
			(stroke
				(width 0.1)
				(type default)
			)
			(layer "F.Fab")
		)
		(fp_line
			(start 0.67945 -0.3048)
			(end 0.67945 0.3048)
			(stroke
				(width 0.1)
				(type default)
			)
			(layer "F.Fab")
		)
		(fp_line
			(start 0.67945 0.3048)
			(end 0.120396 0.3048)
			(stroke
				(width 0.1)
				(type default)
			)
			(layer "F.Fab")
		)
		(pad "1" smd circle
			(at -0.40005 0)
			(size 0 0)
			(layers "F.Cu" "F.Mask" "F.Paste")
			(net "P3V3_AUX")
		)
		(pad "2" smd circle
			(at 0.40005 0)
			(size 0 0)
			(layers "F.Cu" "F.Mask" "F.Paste")
			(net "PU_PCH_PMCALERT_N")
		)
	)
)
